# SCM (Grand Teton) — schematic netlist excerpt (pin names and nets, part order shuffled) for the footprints in the layout excerpt that follows; sources: Cadence DE-HDL packaged netlist, KiCad conversion of 12092022_DA0F0TMDCD0_F0T_Management_Board_D_brd_V3_OCP.brd

C28  Q_CAP  1UF 25V 10% EMPTY  pkg C0402  page 50 : A = REAR_AC_PWR_BTN_N ; B = GND

D12  BZA462A  EMPTY  pkg SOT457XA  page 23
  \1\  = CRT_VCC5
  \2\  = GND
  \3\  = CRT_VCC5
  \4\  = CRT_VCC5
  \5\  = GND
  \6\  = CRT_VCC5

(kicad_pcb
	(version 20260206)
	(generator "pcbnew")
	(generator_version "10.0")
	(general
		(thickness 1.6)
		(legacy_teardrops no)
	)
	(paper "A4")
	(title_block
		(title "12092022_DA0F0TMDCD0_F0T_Management_Board_D_brd_V3_OCP.brd")
		(comment 1 "Grand Teton / footprints 235-236 of 1440")
	)
	(layers
		(0 "F.Cu" signal "TOP")
		(4 "In1.Cu" signal "GND")
		(6 "In2.Cu" signal "IN1")
		(8 "In3.Cu" signal "GND1")
		(10 "In4.Cu" signal "IN2")
		(12 "In5.Cu" signal "VCC")
		(14 "In6.Cu" signal "VCC1")
		(16 "In7.Cu" signal "IN3")
		(18 "In8.Cu" signal "GND2")
		(20 "In9.Cu" signal "IN4")
		(22 "In10.Cu" signal "GND3")
		(2 "B.Cu" signal "BOTTOM")
		(9 "F.Adhes" user "F.Adhesive")
		(11 "B.Adhes" user "B.Adhesive")
		(13 "F.Paste" user "Package Geometry/Pastemask Top")
		(15 "B.Paste" user "Package Geometry/Pastemask Bottom")
		(5 "F.SilkS" user "Ref Des/Silkscreen Top")
		(7 "B.SilkS" user "Ref Des/Silkscreen Bottom")
		(1 "F.Mask" user "Board Geometry/Soldermask Top")
		(3 "B.Mask" user "Board Geometry/Soldermask Bottom")
		(17 "Dwgs.User" user "User.Drawings")
		(19 "Cmts.User" user "User.Comments")
		(21 "Eco1.User" user "User.Eco1")
		(23 "Eco2.User" user "User.Eco2")
		(25 "Edge.Cuts" user "Board Geometry/Outline")
		(27 "Margin" user)
		(31 "F.CrtYd" user "Package Geometry/Place Bound Top")
		(29 "B.CrtYd" user "Package Geometry/Place Bound Bottom")
		(35 "F.Fab" user "Ref Des/Assembly Top")
		(33 "B.Fab" user "Ref Des/Assembly Bottom")
	)
	(footprint ""
		(layer "F.Cu")
		(at 72.644 -16.256 90)
		(property "Reference" "C28"
			(at 0 0 90)
			(layer "F.SilkS")
			(hide yes)
			(effects
				(font
					(size 1.27 1.27)
				)
			)
		)
		(property "Value" ""
			(at 0 0 90)
			(layer "F.Fab")
			(effects
				(font
					(size 1.27 1.27)
				)
			)
		)
		(duplicate_pad_numbers_are_jumpers no)
		(fp_line
			(start 0.7874 -0.4064)
			(end 0.7874 0.4064)
			(stroke
				(width 0.1524)
				(type default)
			)
			(layer "F.SilkS")
		)
		(fp_line
			(start -0.7874 -0.4064)
			(end 0.7874 -0.4064)
			(stroke
				(width 0.1524)
				(type default)
			)
			(layer "F.SilkS")
		)
		(fp_line
			(start 0.7874 0.4064)
			(end -0.7874 0.4064)
			(stroke
				(width 0.1524)
				(type default)
			)
			(layer "F.SilkS")
		)
		(fp_line
			(start -0.7874 0.4064)
			(end -0.7874 -0.4064)
			(stroke
				(width 0.1524)
				(type default)
			)
			(layer "F.SilkS")
		)
		(fp_line
			(start -0.12065 -0.305054)
			(end -0.12065 -0.2794)
			(stroke
				(width 0.1)
				(type default)
			)
			(layer "F.Fab")
		)
		(fp_line
			(start -0.67945 -0.305054)
			(end -0.12065 -0.305054)
			(stroke
				(width 0.1)
				(type default)
			)
			(layer "F.Fab")
		)
		(fp_line
			(start 0.67945 -0.3048)
			(end 0.67945 0.3048)
			(stroke
				(width 0.1)
				(type default)
			)
			(layer "F.Fab")
		)
		(fp_line
			(start 0.12065 -0.3048)
			(end 0.67945 -0.3048)
			(stroke
				(width 0.1)
				(type default)
			)
			(layer "F.Fab")
		)
		(fp_line
			(start 0.12065 -0.2794)
			(end 0.12065 -0.3048)
			(stroke
				(width 0.1)
				(type default)
			)
			(layer "F.Fab")
		)
		(fp_line
			(start -0.12065 -0.2794)
			(end 0.12065 -0.2794)
			(stroke
				(width 0.1)
				(type default)
			)
			(layer "F.Fab")
		)
		(fp_line
			(start 0.120396 0.2794)
			(end -0.12065 0.2794)
			(stroke
				(width 0.1)
				(type default)
			)
			(layer "F.Fab")
		)
		(fp_line
			(start -0.12065 0.2794)
			(end -0.12065 0.3048)
			(stroke
				(width 0.1)
				(type default)
			)
			(layer "F.Fab")
		)
		(fp_line
			(start 0.67945 0.3048)
			(end 0.120396 0.3048)
			(stroke
				(width 0.1)
				(type default)
			)
			(layer "F.Fab")
		)
		(fp_line
			(start 0.120396 0.3048)
			(end 0.120396 0.2794)
			(stroke
				(width 0.1)
				(type default)
			)
			(layer "F.Fab")
		)
		(fp_line
			(start -0.12065 0.3048)
			(end -0.67945 0.3048)
			(stroke
				(width 0.1)
				(type default)
			)
			(layer "F.Fab")
		)
		(fp_line
			(start -0.67945 0.3048)
			(end -0.67945 -0.305054)
			(stroke
				(width 0.1)
				(type default)
			)
			(layer "F.Fab")
		)
		(pad "1" smd circle
			(at -0.40005 0 90)
			(size 0 0)
			(layers "F.Cu" "F.Mask" "F.Paste")
			(net "REAR_AC_PWR_BTN_N")
		)
		(pad "2" smd circle
			(at 0.40005 0 90)
			(size 0 0)
			(layers "F.Cu" "F.Mask" "F.Paste")
			(net "GND")
		)
	)
	(footprint ""
		(layer "F.Cu")
		(at 29.591 -22.9108 -90)
		(property "Reference" "D12"
			(at 1.27 -2.524252 90)
			(unlocked yes)
			(layer "F.SilkS")
			(effects
				(font
					(size 0.7874 0.5842)
					(thickness 0.1524)
				)
				(justify left)
			)
		)
		(property "Value" ""
			(at 0 0 270)
			(layer "F.Fab")
			(effects
				(font
					(size 1.27 1.27)
				)
			)
		)
		(duplicate_pad_numbers_are_jumpers no)
		(fp_line
			(start -1.7272 1.634744)
			(end -1.7272 -1.665224)
			(stroke
				(width 0.1524)
				(type default)
			)
			(layer "F.SilkS")
		)
		(fp_line
			(start 1.739646 1.634744)
			(end -1.7272 1.634744)
			(stroke
				(width 0.1524)
				(type default)
			)
			(layer "F.SilkS")
		)
		(fp_line
			(start 0 -0.930148)
			(end 0.571246 -1.665224)
			(stroke
				(width 0.1524)
				(type default)
			)
			(layer "F.SilkS")
		)
		(fp_line
			(start -1.7272 -1.665224)
			(end -0.5588 -1.665224)
			(stroke
				(width 0.1524)
				(type default)
			)
			(layer "F.SilkS")
		)
		(fp_line
			(start -0.5588 -1.665224)
			(end 0 -0.930148)
			(stroke
				(width 0.1524)
				(type default)
			)
			(layer "F.SilkS")
		)
		(fp_line
			(start 0.571246 -1.665224)
			(end 1.739646 -1.665224)
			(stroke
				(width 0.1524)
				(type default)
			)
			(layer "F.SilkS")
		)
		(fp_line
			(start 1.739646 -1.665224)
			(end 1.739646 1.634744)
			(stroke
				(width 0.1524)
				(type default)
			)
			(layer "F.SilkS")
		)
		(fp_poly
			(pts
				(xy -1.5748 -2.772664) (xy -0.8128 -2.772664) (xy -1.1938 -2.010664)
			)
			(stroke
				(width 0)
				(type default)
			)
			(fill yes)
			(layer "F.SilkS")
		)
		(fp_line
			(start -0.843788 1.534922)
			(end -0.843788 -1.565148)
			(stroke
				(width 0.1)
				(type default)
			)
			(layer "F.Fab")
		)
		(fp_line
			(start 0.856234 1.534922)
			(end -0.843788 1.534922)
			(stroke
				(width 0.1)
				(type default)
			)
			(layer "F.Fab")
		)
		(fp_line
			(start -0.843788 -1.565148)
			(end 0.856234 -1.565148)
			(stroke
				(width 0.1)
				(type default)
			)
			(layer "F.Fab")
		)
		(fp_line
			(start 0.856234 -1.565148)
			(end 0.856234 1.534922)
			(stroke
				(width 0.1)
				(type default)
			)
			(layer "F.Fab")
		)
		(fp_poly
			(pts
				(xy -2.747264 -0.5842) (xy -2.747264 -1.3462) (xy -1.985264 -0.9652)
			)
			(stroke
				(width 0)
				(type default)
			)
			(fill yes)
			(layer "F.Fab")
		)
		(pad "1" smd rect
			(at -1.1938 -0.9652 180)
			(size 0.5588 0.8128)
			(layers "F.Cu" "F.Mask" "F.Paste")
			(net "CRT_VCC5")
		)
		(pad "2" smd rect
			(at -1.1938 -0.01524 180)
			(size 0.5588 0.8128)
			(layers "F.Cu" "F.Mask" "F.Paste")
			(net "GND")
		)
		(pad "3" smd rect
			(at -1.1938 0.93472 180)
			(size 0.5588 0.8128)
			(layers "F.Cu" "F.Mask" "F.Paste")
			(net "CRT_VCC5")
		)
		(pad "4" smd rect
			(at 1.206246 0.93472 180)
			(size 0.5588 0.8128)
			(layers "F.Cu" "F.Mask" "F.Paste")
			(net "CRT_VCC5")
		)
		(pad "5" smd rect
			(at 1.206246 -0.01524 180)
			(size 0.5588 0.8128)
			(layers "F.Cu" "F.Mask" "F.Paste")
			(net "GND")
		)
		(pad "6" smd rect
			(at 1.206246 -0.9652 180)
			(size 0.5588 0.8128)
			(layers "F.Cu" "F.Mask" "F.Paste")
			(net "CRT_VCC5")
		)
	)
)
